(kicad_pcb
	(version 20260206)
	(generator "pcbnew")
	(generator_version "10.0")
	(general
		(thickness 1.6)
		(legacy_teardrops no)
	)
	(paper "A4")
	(title_block
		(title "04192023_DAF0TMB3IC0_F0TG_MB_C_brd_V02_OCP.brd")
		(comment 1 "Grand Teton / footprint 3955 of 8354 (U25), pads 867-975 of 6102")
	)
	(layers
		(0 "F.Cu" signal "TOP")
		(4 "In1.Cu" signal "GND")
		(6 "In2.Cu" signal "IN1")
		(8 "In3.Cu" signal "GND1")
		(10 "In4.Cu" signal "IN2")
		(12 "In5.Cu" signal "GND2")
		(14 "In6.Cu" signal "IN3")
		(16 "In7.Cu" signal "GND3")
		(18 "In8.Cu" signal "VCC")
		(20 "In9.Cu" signal "VCC1")
		(22 "In10.Cu" signal "GND4")
		(24 "In11.Cu" signal "IN4")
		(26 "In12.Cu" signal "GND5")
		(28 "In13.Cu" signal "IN5")
		(30 "In14.Cu" signal "GND6")
		(32 "In15.Cu" signal "IN6")
		(34 "In16.Cu" signal "GND7")
		(2 "B.Cu" signal "BOTTOM")
		(9 "F.Adhes" user "F.Adhesive")
		(11 "B.Adhes" user "B.Adhesive")
		(13 "F.Paste" user "Package Geometry/Pastemask Top")
		(15 "B.Paste" user "Package Geometry/Pastemask Bottom")
		(5 "F.SilkS" user "Ref Des/Silkscreen Top")
		(7 "B.SilkS" user "Ref Des/Silkscreen Bottom")
		(1 "F.Mask" user "Board Geometry/Soldermask Top")
		(3 "B.Mask" user "Board Geometry/Soldermask Bottom")
		(17 "Dwgs.User" user "User.Drawings")
		(19 "Cmts.User" user "User.Comments")
		(21 "Eco1.User" user "User.Eco1")
		(23 "Eco2.User" user "User.Eco2")
		(25 "Edge.Cuts" user "Board Geometry/Outline")
		(27 "Margin" user)
		(31 "F.CrtYd" user "Package Geometry/Place Bound Top")
		(29 "B.CrtYd" user "Package Geometry/Place Bound Bottom")
		(35 "F.Fab" user "Ref Des/Assembly Top")
		(33 "B.Fab" user "Ref Des/Assembly Bottom")
	)
	(footprint ""
		(layer "F.Cu")
		(at 359.867962 -258.880102 180)
		(property "Reference" "U25"
			(at -45.78477 -62.086744 0)
			(unlocked yes)
			(layer "F.SilkS")
			(effects
				(font
					(size 0.7874 0.5842)
					(thickness 0.1524)
				)
			)
		)
		(property "Value" ""
			(at 0 0 180)
			(layer "F.Fab")
			(effects
				(font
					(size 1.27 1.27)
				)
			)
		)
		(duplicate_pad_numbers_are_jumpers no)
		(pad "AM14" smd circle
			(at -22.409912 -11.700002 180)
			(size 0.450088 0.450088)
			(layers "F.Cu" "F.Mask" "F.Paste")
			(net "M_H_CPU0_SA_DQS_DN<9>")
		)
		(pad "AM15" smd circle
			(at -21.470112 -11.700002 180)
			(size 0.450088 0.450088)
			(layers "F.Cu" "F.Mask" "F.Paste")
			(net "GND")
		)
		(pad "AM16" smd circle
			(at -20.530058 -11.700002 180)
			(size 0.450088 0.450088)
			(layers "F.Cu" "F.Mask" "F.Paste")
			(net "M_J_CPU0_SA_DQS_DN<4>")
		)
		(pad "AM17" smd circle
			(at -19.590004 -11.700002 180)
			(size 0.450088 0.450088)
			(layers "F.Cu" "F.Mask" "F.Paste")
			(net "GND")
		)
		(pad "AM18" smd circle
			(at -18.64995 -11.700002 180)
			(size 0.450088 0.450088)
			(layers "F.Cu" "F.Mask" "F.Paste")
			(net "M_J_CPU0_SA_DQS_DN<9>")
		)
		(pad "AM19" smd circle
			(at -17.709896 -11.700002 180)
			(size 0.450088 0.450088)
			(layers "F.Cu" "F.Mask" "F.Paste")
			(net "PVDDCR_SOC_P0")
		)
		(pad "AM20" smd circle
			(at -16.770096 -11.700002 180)
			(size 0.450088 0.450088)
			(layers "F.Cu" "F.Mask" "F.Paste")
			(net "M_I_CPU0_SA_DQS_DN<4>")
		)
		(pad "AM21" smd circle
			(at -15.830042 -11.700002 180)
			(size 0.450088 0.450088)
			(layers "F.Cu" "F.Mask" "F.Paste")
			(net "M_I_CPU0_SA_DQS_DN<9>")
		)
		(pad "AM22" smd circle
			(at -14.889988 -11.700002 180)
			(size 0.450088 0.450088)
			(layers "F.Cu" "F.Mask" "F.Paste")
			(net "PVDDCR_SOC_P0")
		)
		(pad "AM23" smd circle
			(at -13.949934 -11.700002 180)
			(size 0.450088 0.450088)
			(layers "F.Cu" "F.Mask" "F.Paste")
			(net "GND")
		)
		(pad "AM24" smd circle
			(at -13.00988 -11.700002 180)
			(size 0.450088 0.450088)
			(layers "F.Cu" "F.Mask" "F.Paste")
			(net "GND")
		)
		(pad "AM25" smd circle
			(at -12.07008 -11.700002 180)
			(size 0.450088 0.450088)
			(layers "F.Cu" "F.Mask" "F.Paste")
			(net "GND")
		)
		(pad "AM26" smd circle
			(at -11.130026 -11.700002 180)
			(size 0.450088 0.450088)
			(layers "F.Cu" "F.Mask" "F.Paste")
			(net "GND")
		)
		(pad "AM27" smd circle
			(at -10.189972 -11.700002 180)
			(size 0.450088 0.450088)
			(layers "F.Cu" "F.Mask" "F.Paste")
			(net "GND")
		)
		(pad "AM28" smd circle
			(at -9.249918 -11.700002 180)
			(size 0.450088 0.450088)
			(layers "F.Cu" "F.Mask" "F.Paste")
			(net "GND")
		)
		(pad "AM29" smd circle
			(at -8.310118 -11.700002 180)
			(size 0.450088 0.450088)
			(layers "F.Cu" "F.Mask" "F.Paste")
			(net "GND")
		)
		(pad "AM30" smd circle
			(at -7.370064 -11.700002 180)
			(size 0.450088 0.450088)
			(layers "F.Cu" "F.Mask" "F.Paste")
			(net "GND")
		)
		(pad "AM31" smd circle
			(at -6.43001 -11.700002 180)
			(size 0.450088 0.450088)
			(layers "F.Cu" "F.Mask" "F.Paste")
			(net "GND")
		)
		(pad "AM32" smd circle
			(at -5.489956 -11.700002 180)
			(size 0.450088 0.450088)
			(layers "F.Cu" "F.Mask" "F.Paste")
			(net "GND")
		)
		(pad "AM33" smd circle
			(at -4.549902 -11.700002 180)
			(size 0.450088 0.450088)
			(layers "F.Cu" "F.Mask" "F.Paste")
			(net "GND")
		)
		(pad "AM34" smd circle
			(at -3.610102 -11.700002 180)
			(size 0.450088 0.450088)
			(layers "F.Cu" "F.Mask" "F.Paste")
			(net "GND")
		)
		(pad "AM35" smd circle
			(at -2.670048 -11.700002 180)
			(size 0.450088 0.450088)
			(layers "F.Cu" "F.Mask" "F.Paste")
			(net "P5E_CPU0_G3_RX_DN<14>")
		)
		(pad "AM36" smd circle
			(at -1.729994 -11.700002 180)
			(size 0.450088 0.450088)
			(layers "F.Cu" "F.Mask" "F.Paste")
			(net "P5E_CPU0_G3_RX_DP<14>")
		)
		(pad "AM37" smd circle
			(at -0.78994 -11.700002 180)
			(size 0.450088 0.450088)
			(layers "F.Cu" "F.Mask" "F.Paste")
			(net "GND")
		)
		(pad "AM39" smd circle
			(at 1.089914 -11.700002 180)
			(size 0.450088 0.450088)
			(layers "F.Cu" "F.Mask" "F.Paste")
			(net "GND")
		)
		(pad "AM40" smd circle
			(at 2.029968 -11.700002 180)
			(size 0.450088 0.450088)
			(layers "F.Cu" "F.Mask" "F.Paste")
			(net "GMI_CPU0_G1_CPU1_G3_TX_DP<1>")
		)
		(pad "AM41" smd circle
			(at 2.970022 -11.700002 180)
			(size 0.450088 0.450088)
			(layers "F.Cu" "F.Mask" "F.Paste")
			(net "GMI_CPU0_G1_CPU1_G3_TX_DN<1>")
		)
		(pad "AM42" smd circle
			(at 3.910076 -11.700002 180)
			(size 0.450088 0.450088)
			(layers "F.Cu" "F.Mask" "F.Paste")
			(net "GND")
		)
		(pad "AM43" smd circle
			(at 4.849876 -11.700002 180)
			(size 0.450088 0.450088)
			(layers "F.Cu" "F.Mask" "F.Paste")
			(net "GND")
		)
		(pad "AM44" smd circle
			(at 5.78993 -11.700002 180)
			(size 0.450088 0.450088)
			(layers "F.Cu" "F.Mask" "F.Paste")
			(net "GND")
		)
		(pad "AM45" smd circle
			(at 6.729984 -11.700002 180)
			(size 0.450088 0.450088)
			(layers "F.Cu" "F.Mask" "F.Paste")
			(net "GND")
		)
		(pad "AM46" smd circle
			(at 7.670038 -11.700002 180)
			(size 0.450088 0.450088)
			(layers "F.Cu" "F.Mask" "F.Paste")
			(net "GND")
		)
		(pad "AM47" smd circle
			(at 8.610092 -11.700002 180)
			(size 0.450088 0.450088)
			(layers "F.Cu" "F.Mask" "F.Paste")
			(net "GND")
		)
		(pad "AM48" smd circle
			(at 9.549892 -11.700002 180)
			(size 0.450088 0.450088)
			(layers "F.Cu" "F.Mask" "F.Paste")
			(net "GND")
		)
		(pad "AM49" smd circle
			(at 10.489946 -11.700002 180)
			(size 0.450088 0.450088)
			(layers "F.Cu" "F.Mask" "F.Paste")
			(net "GND")
		)
		(pad "AM50" smd circle
			(at 11.43 -11.700002 180)
			(size 0.450088 0.450088)
			(layers "F.Cu" "F.Mask" "F.Paste")
			(net "GND")
		)
		(pad "AM51" smd circle
			(at 12.370054 -11.700002 180)
			(size 0.450088 0.450088)
			(layers "F.Cu" "F.Mask" "F.Paste")
			(net "GND")
		)
		(pad "AM52" smd circle
			(at 13.310108 -11.700002 180)
			(size 0.450088 0.450088)
			(layers "F.Cu" "F.Mask" "F.Paste")
			(net "GND")
		)
		(pad "AM53" smd circle
			(at 14.249908 -11.700002 180)
			(size 0.450088 0.450088)
			(layers "F.Cu" "F.Mask" "F.Paste")
			(net "GND")
		)
		(pad "AM54" smd circle
			(at 15.189962 -11.700002 180)
			(size 0.450088 0.450088)
			(layers "F.Cu" "F.Mask" "F.Paste")
			(net "PVDDIO_P0")
		)
		(pad "AM55" smd circle
			(at 16.130016 -11.700002 180)
			(size 0.450088 0.450088)
			(layers "F.Cu" "F.Mask" "F.Paste")
			(net "M_C_CPU0_SA_DQS_DN<9>")
		)
		(pad "AM56" smd circle
			(at 17.07007 -11.700002 180)
			(size 0.450088 0.450088)
			(layers "F.Cu" "F.Mask" "F.Paste")
			(net "M_C_CPU0_SA_DQS_DN<4>")
		)
		(pad "AM57" smd circle
			(at 18.010124 -11.700002 180)
			(size 0.450088 0.450088)
			(layers "F.Cu" "F.Mask" "F.Paste")
			(net "PVDDIO_P0")
		)
		(pad "AM58" smd circle
			(at 18.949924 -11.700002 180)
			(size 0.450088 0.450088)
			(layers "F.Cu" "F.Mask" "F.Paste")
			(net "M_D_CPU0_SA_DQS_DN<9>")
		)
		(pad "AM59" smd circle
			(at 19.889978 -11.700002 180)
			(size 0.450088 0.450088)
			(layers "F.Cu" "F.Mask" "F.Paste")
			(net "GND")
		)
		(pad "AM60" smd circle
			(at 20.830032 -11.700002 180)
			(size 0.450088 0.450088)
			(layers "F.Cu" "F.Mask" "F.Paste")
			(net "M_D_CPU0_SA_DQS_DN<4>")
		)
		(pad "AM61" smd circle
			(at 21.770086 -11.700002 180)
			(size 0.450088 0.450088)
			(layers "F.Cu" "F.Mask" "F.Paste")
			(net "GND")
		)
		(pad "AM62" smd circle
			(at 22.709886 -11.700002 180)
			(size 0.450088 0.450088)
			(layers "F.Cu" "F.Mask" "F.Paste")
			(net "M_B_CPU0_SA_DQS_DN<9>")
		)
		(pad "AM63" smd circle
			(at 23.64994 -11.700002 180)
			(size 0.450088 0.450088)
			(layers "F.Cu" "F.Mask" "F.Paste")
			(net "M_B_CPU0_SA_DQS_DN<4>")
		)
		(pad "AM64" smd circle
			(at 24.589994 -11.700002 180)
			(size 0.450088 0.450088)
			(layers "F.Cu" "F.Mask" "F.Paste")
			(net "PVDDIO_P0")
		)
		(pad "AM65" smd circle
			(at 25.530048 -11.700002 180)
			(size 0.450088 0.450088)
			(layers "F.Cu" "F.Mask" "F.Paste")
			(net "M_F_CPU0_SA_DQS_DN<9>")
		)
		(pad "AM66" smd circle
			(at 26.470102 -11.700002 180)
			(size 0.450088 0.450088)
			(layers "F.Cu" "F.Mask" "F.Paste")
			(net "GND")
		)
		(pad "AM67" smd circle
			(at 27.409902 -11.700002 180)
			(size 0.450088 0.450088)
			(layers "F.Cu" "F.Mask" "F.Paste")
			(net "M_F_CPU0_SA_DQS_DN<4>")
		)
		(pad "AM68" smd circle
			(at 28.349956 -11.700002 180)
			(size 0.450088 0.450088)
			(layers "F.Cu" "F.Mask" "F.Paste")
			(net "GND")
		)
		(pad "AM69" smd circle
			(at 29.29001 -11.700002 180)
			(size 0.450088 0.450088)
			(layers "F.Cu" "F.Mask" "F.Paste")
			(net "M_E_CPU0_SA_DQS_DN<9>")
		)
		(pad "AM70" smd circle
			(at 30.230064 -11.700002 180)
			(size 0.450088 0.450088)
			(layers "F.Cu" "F.Mask" "F.Paste")
			(net "M_E_CPU0_SA_DQS_DN<4>")
		)
		(pad "AM71" smd circle
			(at 31.170118 -11.700002 180)
			(size 0.450088 0.450088)
			(layers "F.Cu" "F.Mask" "F.Paste")
			(net "PVDDIO_P0")
		)
		(pad "AM72" smd circle
			(at 32.109918 -11.700002 180)
			(size 0.450088 0.450088)
			(layers "F.Cu" "F.Mask" "F.Paste")
			(net "M_A_CPU0_SA_DQS_DN<9>")
		)
		(pad "AM73" smd circle
			(at 33.049972 -11.700002 180)
			(size 0.450088 0.450088)
			(layers "F.Cu" "F.Mask" "F.Paste")
			(net "GND")
		)
		(pad "AM74" smd circle
			(at 33.990026 -11.700002 180)
			(size 0.450088 0.450088)
			(layers "F.Cu" "F.Mask" "F.Paste")
			(net "M_A_CPU0_SA_DQS_DN<4>")
		)
		(pad "AN1" smd circle
			(at -34.159952 -10.889996 180)
			(size 0.450088 0.450088)
			(layers "F.Cu" "F.Mask" "F.Paste")
			(net "GND")
		)
		(pad "AN2" smd circle
			(at -33.219898 -10.889996 180)
			(size 0.450088 0.450088)
			(layers "F.Cu" "F.Mask" "F.Paste")
			(net "M_G_CPU0_SA_CB<4>")
		)
		(pad "AN3" smd circle
			(at -32.280098 -10.889996 180)
			(size 0.450088 0.450088)
			(layers "F.Cu" "F.Mask" "F.Paste")
			(net "M_G_CPU0_SA_DQS_DP<9>")
		)
		(pad "AN4" smd circle
			(at -31.340044 -10.889996 180)
			(size 0.450088 0.450088)
			(layers "F.Cu" "F.Mask" "F.Paste")
			(net "GND")
		)
		(pad "AN5" smd circle
			(at -30.39999 -10.889996 180)
			(size 0.450088 0.450088)
			(layers "F.Cu" "F.Mask" "F.Paste")
			(net "M_K_CPU0_SA_CB<4>")
		)
		(pad "AN6" smd circle
			(at -29.459936 -10.889996 180)
			(size 0.450088 0.450088)
			(layers "F.Cu" "F.Mask" "F.Paste")
			(net "GND")
		)
		(pad "AN7" smd circle
			(at -28.519882 -10.889996 180)
			(size 0.450088 0.450088)
			(layers "F.Cu" "F.Mask" "F.Paste")
			(net "M_K_CPU0_SA_DQS_DP<9>")
		)
		(pad "AN8" smd circle
			(at -27.580082 -10.889996 180)
			(size 0.450088 0.450088)
			(layers "F.Cu" "F.Mask" "F.Paste")
			(net "GND")
		)
		(pad "AN9" smd circle
			(at -26.640028 -10.889996 180)
			(size 0.450088 0.450088)
			(layers "F.Cu" "F.Mask" "F.Paste")
			(net "M_L_CPU0_SA_CB<4>")
		)
		(pad "AN10" smd circle
			(at -25.699974 -10.889996 180)
			(size 0.450088 0.450088)
			(layers "F.Cu" "F.Mask" "F.Paste")
			(net "M_L_CPU0_SA_DQS_DP<9>")
		)
		(pad "AN11" smd circle
			(at -24.75992 -10.889996 180)
			(size 0.450088 0.450088)
			(layers "F.Cu" "F.Mask" "F.Paste")
			(net "GND")
		)
		(pad "AN12" smd circle
			(at -23.82012 -10.889996 180)
			(size 0.450088 0.450088)
			(layers "F.Cu" "F.Mask" "F.Paste")
			(net "M_H_CPU0_SA_CB<4>")
		)
		(pad "AN13" smd circle
			(at -22.880066 -10.889996 180)
			(size 0.450088 0.450088)
			(layers "F.Cu" "F.Mask" "F.Paste")
			(net "GND")
		)
		(pad "AN14" smd circle
			(at -21.940012 -10.889996 180)
			(size 0.450088 0.450088)
			(layers "F.Cu" "F.Mask" "F.Paste")
			(net "M_H_CPU0_SA_DQS_DP<9>")
		)
		(pad "AN15" smd circle
			(at -20.999958 -10.889996 180)
			(size 0.450088 0.450088)
			(layers "F.Cu" "F.Mask" "F.Paste")
			(net "GND")
		)
		(pad "AN16" smd circle
			(at -20.059904 -10.889996 180)
			(size 0.450088 0.450088)
			(layers "F.Cu" "F.Mask" "F.Paste")
			(net "M_J_CPU0_SA_CB<4>")
		)
		(pad "AN17" smd circle
			(at -19.120104 -10.889996 180)
			(size 0.450088 0.450088)
			(layers "F.Cu" "F.Mask" "F.Paste")
			(net "M_J_CPU0_SA_DQS_DP<9>")
		)
		(pad "AN18" smd circle
			(at -18.18005 -10.889996 180)
			(size 0.450088 0.450088)
			(layers "F.Cu" "F.Mask" "F.Paste")
			(net "GND")
		)
		(pad "AN19" smd circle
			(at -17.239996 -10.889996 180)
			(size 0.450088 0.450088)
			(layers "F.Cu" "F.Mask" "F.Paste")
			(net "M_I_CPU0_SA_CB<4>")
		)
		(pad "AN20" smd circle
			(at -16.299942 -10.889996 180)
			(size 0.450088 0.450088)
			(layers "F.Cu" "F.Mask" "F.Paste")
			(net "GND")
		)
		(pad "AN21" smd circle
			(at -15.359888 -10.889996 180)
			(size 0.450088 0.450088)
			(layers "F.Cu" "F.Mask" "F.Paste")
			(net "M_I_CPU0_SA_DQS_DP<9>")
		)
		(pad "AN22" smd circle
			(at -14.420088 -10.889996 180)
			(size 0.450088 0.450088)
			(layers "F.Cu" "F.Mask" "F.Paste")
			(net "GND")
		)
		(pad "AN23" smd circle
			(at -13.480034 -10.889996 180)
			(size 0.450088 0.450088)
			(layers "F.Cu" "F.Mask" "F.Paste")
			(net "P5E_CPU0_G3_RX_DN<2>")
		)
		(pad "AN24" smd circle
			(at -12.53998 -10.889996 180)
			(size 0.450088 0.450088)
			(layers "F.Cu" "F.Mask" "F.Paste")
			(net "P5E_CPU0_G3_RX_DP<2>")
		)
		(pad "AN25" smd circle
			(at -11.599926 -10.889996 180)
			(size 0.450088 0.450088)
			(layers "F.Cu" "F.Mask" "F.Paste")
			(net "GND")
		)
		(pad "AN26" smd circle
			(at -10.659872 -10.889996 180)
			(size 0.450088 0.450088)
			(layers "F.Cu" "F.Mask" "F.Paste")
			(net "P5E_CPU0_G3_RX_DN<5>")
		)
		(pad "AN27" smd circle
			(at -9.720072 -10.889996 180)
			(size 0.450088 0.450088)
			(layers "F.Cu" "F.Mask" "F.Paste")
			(net "P5E_CPU0_G3_RX_DP<5>")
		)
		(pad "AN28" smd circle
			(at -8.780018 -10.889996 180)
			(size 0.450088 0.450088)
			(layers "F.Cu" "F.Mask" "F.Paste")
			(net "GND")
		)
		(pad "AN29" smd circle
			(at -7.839964 -10.889996 180)
			(size 0.450088 0.450088)
			(layers "F.Cu" "F.Mask" "F.Paste")
			(net "P5E_CPU0_G3_RX_DN<8>")
		)
		(pad "AN30" smd circle
			(at -6.89991 -10.889996 180)
			(size 0.450088 0.450088)
			(layers "F.Cu" "F.Mask" "F.Paste")
			(net "P5E_CPU0_G3_RX_DP<8>")
		)
		(pad "AN31" smd circle
			(at -5.96011 -10.889996 180)
			(size 0.450088 0.450088)
			(layers "F.Cu" "F.Mask" "F.Paste")
			(net "GND")
		)
		(pad "AN32" smd circle
			(at -5.020056 -10.889996 180)
			(size 0.450088 0.450088)
			(layers "F.Cu" "F.Mask" "F.Paste")
			(net "P5E_CPU0_G3_RX_DN<11>")
		)
		(pad "AN33" smd circle
			(at -4.080002 -10.889996 180)
			(size 0.450088 0.450088)
			(layers "F.Cu" "F.Mask" "F.Paste")
			(net "P5E_CPU0_G3_RX_DP<11>")
		)
		(pad "AN34" smd circle
			(at -3.139948 -10.889996 180)
			(size 0.450088 0.450088)
			(layers "F.Cu" "F.Mask" "F.Paste")
			(net "GND")
		)
		(pad "AN35" smd circle
			(at -2.199894 -10.889996 180)
			(size 0.450088 0.450088)
			(layers "F.Cu" "F.Mask" "F.Paste")
			(net "GND")
		)
		(pad "AN36" smd circle
			(at -1.260094 -10.889996 180)
			(size 0.450088 0.450088)
			(layers "F.Cu" "F.Mask" "F.Paste")
			(net "GND")
		)
		(pad "AN40" smd circle
			(at 1.560068 -10.889996 180)
			(size 0.450088 0.450088)
			(layers "F.Cu" "F.Mask" "F.Paste")
			(net "GND")
		)
		(pad "AN41" smd circle
			(at 2.500122 -10.889996 180)
			(size 0.450088 0.450088)
			(layers "F.Cu" "F.Mask" "F.Paste")
			(net "GND")
		)
		(pad "AN42" smd circle
			(at 3.439922 -10.889996 180)
			(size 0.450088 0.450088)
			(layers "F.Cu" "F.Mask" "F.Paste")
			(net "GND")
		)
		(pad "AN43" smd circle
			(at 4.379976 -10.889996 180)
			(size 0.450088 0.450088)
			(layers "F.Cu" "F.Mask" "F.Paste")
			(net "GMI_CPU0_G1_CPU1_G3_TX_DP<4>")
		)
		(pad "AN44" smd circle
			(at 5.32003 -10.889996 180)
			(size 0.450088 0.450088)
			(layers "F.Cu" "F.Mask" "F.Paste")
			(net "GMI_CPU0_G1_CPU1_G3_TX_DN<4>")
		)
		(pad "AN45" smd circle
			(at 6.260084 -10.889996 180)
			(size 0.450088 0.450088)
			(layers "F.Cu" "F.Mask" "F.Paste")
			(net "GND")
		)
		(pad "AN46" smd circle
			(at 7.199884 -10.889996 180)
			(size 0.450088 0.450088)
			(layers "F.Cu" "F.Mask" "F.Paste")
			(net "GMI_CPU0_G1_CPU1_G3_TX_DP<7>")
		)
		(pad "AN47" smd circle
			(at 8.139938 -10.889996 180)
			(size 0.450088 0.450088)
			(layers "F.Cu" "F.Mask" "F.Paste")
			(net "GMI_CPU0_G1_CPU1_G3_TX_DN<7>")
		)
		(pad "AN48" smd circle
			(at 9.079992 -10.889996 180)
			(size 0.450088 0.450088)
			(layers "F.Cu" "F.Mask" "F.Paste")
			(net "GND")
		)
		(pad "AN49" smd circle
			(at 10.020046 -10.889996 180)
			(size 0.450088 0.450088)
			(layers "F.Cu" "F.Mask" "F.Paste")
			(net "GMI_CPU0_G1_CPU1_G3_TX_DP<10>")
		)
		(pad "AN50" smd circle
			(at 10.9601 -10.889996 180)
			(size 0.450088 0.450088)
			(layers "F.Cu" "F.Mask" "F.Paste")
			(net "GMI_CPU0_G1_CPU1_G3_TX_DN<10>")
		)
		(pad "AN51" smd circle
			(at 11.8999 -10.889996 180)
			(size 0.450088 0.450088)
			(layers "F.Cu" "F.Mask" "F.Paste")
			(net "GND")
		)
		(pad "AN52" smd circle
			(at 12.839954 -10.889996 180)
			(size 0.450088 0.450088)
			(layers "F.Cu" "F.Mask" "F.Paste")
			(net "GMI_CPU0_G1_CPU1_G3_TX_DP<13>")
		)
	)
)
